# T6G (Grand Teton) — schematic netlist excerpt (pin names and nets, part order shuffled) for the footprints in the layout excerpt that follows; sources: Cadence DE-HDL packaged netlist, KiCad conversion of 04192023_DAF0TMB3IC0_F0TG_MB_C_brd_V02_OCP.brd

C2559  Q_CAP  22UF 4V 20% X6S  pkg C0402  page 70 : A = PVDDCR_SOC_P0 ; B = GND
C2578  Q_CAP  22UF 4V 20% X6S  pkg C0402  page 70 : A = PVDDCR_SOC_P0 ; B = GND
C1046  Q_CAP  1UF 4V 20% X6S  pkg 0201  page 312 : A = P0V9_CPU0_RT3_2A ; B = GND

(kicad_pcb
	(version 20260206)
	(generator "pcbnew")
	(generator_version "10.0")
	(general
		(thickness 1.6)
		(legacy_teardrops no)
	)
	(paper "A4")
	(title_block
		(title "04192023_DAF0TMB3IC0_F0TG_MB_C_brd_V02_OCP.brd")
		(comment 1 "Grand Teton / footprints 7275-7277 of 8354")
	)
	(layers
		(0 "F.Cu" signal "TOP")
		(4 "In1.Cu" signal "GND")
		(6 "In2.Cu" signal "IN1")
		(8 "In3.Cu" signal "GND1")
		(10 "In4.Cu" signal "IN2")
		(12 "In5.Cu" signal "GND2")
		(14 "In6.Cu" signal "IN3")
		(16 "In7.Cu" signal "GND3")
		(18 "In8.Cu" signal "VCC")
		(20 "In9.Cu" signal "VCC1")
		(22 "In10.Cu" signal "GND4")
		(24 "In11.Cu" signal "IN4")
		(26 "In12.Cu" signal "GND5")
		(28 "In13.Cu" signal "IN5")
		(30 "In14.Cu" signal "GND6")
		(32 "In15.Cu" signal "IN6")
		(34 "In16.Cu" signal "GND7")
		(2 "B.Cu" signal "BOTTOM")
		(9 "F.Adhes" user "F.Adhesive")
		(11 "B.Adhes" user "B.Adhesive")
		(13 "F.Paste" user "Package Geometry/Pastemask Top")
		(15 "B.Paste" user "Package Geometry/Pastemask Bottom")
		(5 "F.SilkS" user "Ref Des/Silkscreen Top")
		(7 "B.SilkS" user "Ref Des/Silkscreen Bottom")
		(1 "F.Mask" user "Board Geometry/Soldermask Top")
		(3 "B.Mask" user "Board Geometry/Soldermask Bottom")
		(17 "Dwgs.User" user "User.Drawings")
		(19 "Cmts.User" user "User.Comments")
		(21 "Eco1.User" user "User.Eco1")
		(23 "Eco2.User" user "User.Eco2")
		(25 "Edge.Cuts" user "Board Geometry/Outline")
		(27 "Margin" user)
		(31 "F.CrtYd" user "Package Geometry/Place Bound Top")
		(29 "B.CrtYd" user "Package Geometry/Place Bound Bottom")
		(35 "F.Fab" user "Ref Des/Assembly Top")
		(33 "B.Fab" user "Ref Des/Assembly Bottom")
	)
	(footprint ""
		(layer "B.Cu")
		(at 389.683752 -395.148562 90)
		(property "Reference" "C1046"
			(at 0 0 90)
			(layer "B.SilkS")
			(hide yes)
			(effects
				(font
					(size 1.27 1.27)
				)
				(justify mirror)
			)
		)
		(property "Value" ""
			(at 0 0 90)
			(layer "B.Fab")
			(effects
				(font
					(size 1.27 1.27)
				)
				(justify mirror)
			)
		)
		(duplicate_pad_numbers_are_jumpers no)
		(fp_line
			(start 0.299974 -0.150114)
			(end -0.299974 -0.150114)
			(stroke
				(width 0.1)
				(type default)
			)
			(layer "B.Fab")
		)
		(fp_line
			(start -0.299974 -0.150114)
			(end -0.299974 0.150114)
			(stroke
				(width 0.1)
				(type default)
			)
			(layer "B.Fab")
		)
		(fp_line
			(start 0.299974 0.150114)
			(end 0.299974 -0.150114)
			(stroke
				(width 0.1)
				(type default)
			)
			(layer "B.Fab")
		)
		(fp_line
			(start -0.299974 0.150114)
			(end 0.299974 0.150114)
			(stroke
				(width 0.1)
				(type default)
			)
			(layer "B.Fab")
		)
		(pad "1" smd rect
			(at 0.2667 0 270)
			(size 0.3048 0.381)
			(layers "B.Cu" "B.Mask" "B.Paste")
			(net "P0V9_CPU0_RT3_2A")
		)
		(pad "2" smd rect
			(at -0.2667 0 270)
			(size 0.3048 0.381)
			(layers "B.Cu" "B.Mask" "B.Paste")
			(net "GND")
		)
	)
	(footprint ""
		(layer "B.Cu")
		(at 365.835692 -258.405122)
		(property "Reference" "C2559"
			(at 0 0 0)
			(layer "B.SilkS")
			(hide yes)
			(effects
				(font
					(size 1.27 1.27)
				)
				(justify mirror)
			)
		)
		(property "Value" ""
			(at 0 0 0)
			(layer "B.Fab")
			(effects
				(font
					(size 1.27 1.27)
				)
				(justify mirror)
			)
		)
		(duplicate_pad_numbers_are_jumpers no)
		(fp_line
			(start -0.7874 -0.4064)
			(end -0.7874 0.4064)
			(stroke
				(width 0.1524)
				(type default)
			)
			(layer "B.SilkS")
		)
		(fp_line
			(start -0.7874 0.4064)
			(end 0.7874 0.4064)
			(stroke
				(width 0.1524)
				(type default)
			)
			(layer "B.SilkS")
		)
		(fp_line
			(start 0.7874 -0.4064)
			(end -0.7874 -0.4064)
			(stroke
				(width 0.1524)
				(type default)
			)
			(layer "B.SilkS")
		)
		(fp_line
			(start 0.7874 0.4064)
			(end 0.7874 -0.4064)
			(stroke
				(width 0.1524)
				(type default)
			)
			(layer "B.SilkS")
		)
		(fp_line
			(start -0.67945 -0.3048)
			(end -0.67945 0.3048)
			(stroke
				(width 0.1)
				(type default)
			)
			(layer "B.Fab")
		)
		(fp_line
			(start -0.67945 0.3048)
			(end -0.120396 0.3048)
			(stroke
				(width 0.1)
				(type default)
			)
			(layer "B.Fab")
		)
		(fp_line
			(start -0.12065 -0.3048)
			(end -0.67945 -0.3048)
			(stroke
				(width 0.1)
				(type default)
			)
			(layer "B.Fab")
		)
		(fp_line
			(start -0.12065 -0.2794)
			(end -0.12065 -0.3048)
			(stroke
				(width 0.1)
				(type default)
			)
			(layer "B.Fab")
		)
		(fp_line
			(start -0.120396 0.2794)
			(end 0.12065 0.2794)
			(stroke
				(width 0.1)
				(type default)
			)
			(layer "B.Fab")
		)
		(fp_line
			(start -0.120396 0.3048)
			(end -0.120396 0.2794)
			(stroke
				(width 0.1)
				(type default)
			)
			(layer "B.Fab")
		)
		(fp_line
			(start 0.12065 -0.305054)
			(end 0.12065 -0.2794)
			(stroke
				(width 0.1)
				(type default)
			)
			(layer "B.Fab")
		)
		(fp_line
			(start 0.12065 -0.2794)
			(end -0.12065 -0.2794)
			(stroke
				(width 0.1)
				(type default)
			)
			(layer "B.Fab")
		)
		(fp_line
			(start 0.12065 0.2794)
			(end 0.12065 0.3048)
			(stroke
				(width 0.1)
				(type default)
			)
			(layer "B.Fab")
		)
		(fp_line
			(start 0.12065 0.3048)
			(end 0.67945 0.3048)
			(stroke
				(width 0.1)
				(type default)
			)
			(layer "B.Fab")
		)
		(fp_line
			(start 0.67945 -0.305054)
			(end 0.12065 -0.305054)
			(stroke
				(width 0.1)
				(type default)
			)
			(layer "B.Fab")
		)
		(fp_line
			(start 0.67945 0.3048)
			(end 0.67945 -0.305054)
			(stroke
				(width 0.1)
				(type default)
			)
			(layer "B.Fab")
		)
		(pad "1" smd circle
			(at 0.40005 0 180)
			(size 0 0)
			(layers "B.Cu" "B.Mask" "B.Paste")
			(net "PVDDCR_SOC_P0")
		)
		(pad "2" smd circle
			(at -0.40005 0 180)
			(size 0 0)
			(layers "B.Cu" "B.Mask" "B.Paste")
			(net "GND")
		)
	)
	(footprint ""
		(layer "B.Cu")
		(at 373.329454 -255.84531)
		(property "Reference" "C2578"
			(at 0 0 0)
			(layer "B.SilkS")
			(hide yes)
			(effects
				(font
					(size 1.27 1.27)
				)
				(justify mirror)
			)
		)
		(property "Value" ""
			(at 0 0 0)
			(layer "B.Fab")
			(effects
				(font
					(size 1.27 1.27)
				)
				(justify mirror)
			)
		)
		(duplicate_pad_numbers_are_jumpers no)
		(fp_line
			(start -0.7874 -0.4064)
			(end -0.7874 0.4064)
			(stroke
				(width 0.1524)
				(type default)
			)
			(layer "B.SilkS")
		)
		(fp_line
			(start -0.7874 0.4064)
			(end 0.7874 0.4064)
			(stroke
				(width 0.1524)
				(type default)
			)
			(layer "B.SilkS")
		)
		(fp_line
			(start 0.7874 -0.4064)
			(end -0.7874 -0.4064)
			(stroke
				(width 0.1524)
				(type default)
			)
			(layer "B.SilkS")
		)
		(fp_line
			(start 0.7874 0.4064)
			(end 0.7874 -0.4064)
			(stroke
				(width 0.1524)
				(type default)
			)
			(layer "B.SilkS")
		)
		(fp_line
			(start -0.67945 -0.3048)
			(end -0.67945 0.3048)
			(stroke
				(width 0.1)
				(type default)
			)
			(layer "B.Fab")
		)
		(fp_line
			(start -0.67945 0.3048)
			(end -0.120396 0.3048)
			(stroke
				(width 0.1)
				(type default)
			)
			(layer "B.Fab")
		)
		(fp_line
			(start -0.12065 -0.3048)
			(end -0.67945 -0.3048)
			(stroke
				(width 0.1)
				(type default)
			)
			(layer "B.Fab")
		)
		(fp_line
			(start -0.12065 -0.2794)
			(end -0.12065 -0.3048)
			(stroke
				(width 0.1)
				(type default)
			)
			(layer "B.Fab")
		)
		(fp_line
			(start -0.120396 0.2794)
			(end 0.12065 0.2794)
			(stroke
				(width 0.1)
				(type default)
			)
			(layer "B.Fab")
		)
		(fp_line
			(start -0.120396 0.3048)
			(end -0.120396 0.2794)
			(stroke
				(width 0.1)
				(type default)
			)
			(layer "B.Fab")
		)
		(fp_line
			(start 0.12065 -0.305054)
			(end 0.12065 -0.2794)
			(stroke
				(width 0.1)
				(type default)
			)
			(layer "B.Fab")
		)
		(fp_line
			(start 0.12065 -0.2794)
			(end -0.12065 -0.2794)
			(stroke
				(width 0.1)
				(type default)
			)
			(layer "B.Fab")
		)
		(fp_line
			(start 0.12065 0.2794)
			(end 0.12065 0.3048)
			(stroke
				(width 0.1)
				(type default)
			)
			(layer "B.Fab")
		)
		(fp_line
			(start 0.12065 0.3048)
			(end 0.67945 0.3048)
			(stroke
				(width 0.1)
				(type default)
			)
			(layer "B.Fab")
		)
		(fp_line
			(start 0.67945 -0.305054)
			(end 0.12065 -0.305054)
			(stroke
				(width 0.1)
				(type default)
			)
			(layer "B.Fab")
		)
		(fp_line
			(start 0.67945 0.3048)
			(end 0.67945 -0.305054)
			(stroke
				(width 0.1)
				(type default)
			)
			(layer "B.Fab")
		)
		(pad "1" smd circle
			(at 0.40005 0 180)
			(size 0 0)
			(layers "B.Cu" "B.Mask" "B.Paste")
			(net "PVDDCR_SOC_P0")
		)
		(pad "2" smd circle
			(at -0.40005 0 180)
			(size 0 0)
			(layers "B.Cu" "B.Mask" "B.Paste")
			(net "GND")
		)
	)
)
